# S9S_MB_2U (Grand Teton) — schematic netlist excerpt (pin names and nets, part order shuffled) for the footprints in the layout excerpt that follows; sources: Cadence DE-HDL packaged netlist, KiCad conversion of 03242023_DA0F0TMBIJ0_F0T_Motherboard_J_brd_V01_OCP.brd

J3  SCONN288_ADR50017P130CC  SCONN288_ADR50017-P130CC IO  pkg DDR288S_1-1VXB  page 84
  VIN_BULK0  = P12V_S3_AUX_CPU0_NVDIMM
  RFU0  = TP_CHB_CPU0_DIMM1_FRU_0
  VIN_MGMT  = P3V3_AUX
  HSCL  = I3C_SPD_DDRABCD_CPU0_LVC1_SCL_2
  HSDA  = I3C_SPD_DDRABCD_CPU0_LVC1_SDA
  VSS0  = GND
  DQ0_A  = M_B_CPU0_SA_DQ<0>
  VSS1  = GND
  DQ1_A  = M_B_CPU0_SA_DQ<1>
  VSS2  = GND
  DQS0_A_T  = M_B_CPU0_SA_DQS_DP<0>
  DQS0_A_C  = M_B_CPU0_SA_DQS_DN<0>
  VSS3  = GND
  DQ4_A  = M_B_CPU0_SA_DQ<4>
  VSS4  = GND
  DQ5_A  = M_B_CPU0_SA_DQ<5>
  VSS5  = GND
  DQ8_A  = M_B_CPU0_SA_DQ<8>
  VSS6  = GND
  DQ9_A  = M_B_CPU0_SA_DQ<9>
  VSS7  = GND
  DQS1_A_T  = M_B_CPU0_SA_DQS_DP<1>
  DQS1_A_C  = M_B_CPU0_SA_DQS_DN<1>
  VSS8  = GND
  DQ12_A  = M_B_CPU0_SA_DQ<12>
  VSS9  = GND
  DQ13_A  = M_B_CPU0_SA_DQ<13>
  VSS10  = GND
  DQ16_A  = M_B_CPU0_SA_DQ<16>
  VSS11  = GND
  DQ17_A  = M_B_CPU0_SA_DQ<17>
  VSS12  = GND
  DQS2_A_T  = M_B_CPU0_SA_DQS_DP<2>
  DQS2_A_C  = M_B_CPU0_SA_DQS_DN<2>
  VSS13  = GND
  DQ20_A  = M_B_CPU0_SA_DQ<20>
  VSS14  = GND
  DQ21_A  = M_B_CPU0_SA_DQ<21>
  VSS15  = GND
  DQ24_A  = M_B_CPU0_SA_DQ<24>
  VSS16  = GND
  DQ25_A  = M_B_CPU0_SA_DQ<25>
  VSS17  = GND
  DQS3_A_T  = M_B_CPU0_SA_DQS_DP<3>
  DQS3_A_C  = M_B_CPU0_SA_DQS_DN<3>
  VSS18  = GND
  DQ28_A  = M_B_CPU0_SA_DQ<28>
  VSS19  = GND
  DQ29_A  = M_B_CPU0_SA_DQ<29>
  VSS20  = GND
  CB0_A  = M_B_CPU0_SA_CB<0>
  VSS21  = GND
  CB1_A  = M_B_CPU0_SA_CB<1>
  VSS22  = GND
  DQS4_A_T  = M_B_CPU0_SA_DQS_DP<4>
  DQS4_A_C  = M_B_CPU0_SA_DQS_DN<4>
  VSS23  = GND
  CB4_A  = M_B_CPU0_SA_CB<4>
  VSS24  = GND
  CB5_A  = M_B_CPU0_SA_CB<5>
  VSS25  = GND
  ALERT_N  = M_B_CPU0_ALERT_N
  VSS26  = GND
  CS0_A_N  = M_B_CPU0_SA_CS_N<0>
  VSS27  = GND
  CA0_A  = M_B_CPU0_SA_CA<0>
  VSS28  = GND
  CA2_A  = M_B_CPU0_SA_CA<2>
  VSS29  = GND
  CA4_A  = M_B_CPU0_SA_CA<4>
  VSS30  = GND
  CA6_A  = M_B_CPU0_SA_CA<6>
  VSS31  = GND
  PAR_A  = M_B_CPU0_SA_PAR
  VSS32  = GND
  CA0_B  = M_B_CPU0_SB_CA<0>
  VSS33  = GND
  CA2_B  = M_B_CPU0_SB_CA<2>
  VSS34  = GND
  CA4_B  = M_B_CPU0_SB_CA<4>
  VSS35  = GND
  CA6_B  = M_B_CPU0_SB_CA<6>
  VSS36  = GND
  CS0_B_N  = M_B_CPU0_SB_CS_N<0>
  VSS37  = GND
  \lbd||rsp_a_n\  = M_B_CPU0_SA_RSP<0>
  \lbs||rsp_b_n\  = M_B_CPU0_SB_RSP<0>
  VSS38  = GND
  CB4_B  = M_B_CPU0_SB_CB<4>
  VSS39  = GND
  CB5_B  = M_B_CPU0_SB_CB<5>
  VSS40  = GND
  \dqs9_b_t||tdqs9_b_t||dbi4_b_n\  = M_B_CPU0_SB_DQS_DP<9>
  \dqs9_b_c||tdqs9_b_c\  = M_B_CPU0_SB_DQS_DN<9>
  VSS41  = GND
  CB0_B  = M_B_CPU0_SB_CB<0>
  VSS42  = GND
  CB1_B  = M_B_CPU0_SB_CB<1>
  VSS43  = GND
  DQ0_B  = M_B_CPU0_SB_DQ<0>
  VSS44  = GND
  DQ1_B  = M_B_CPU0_SB_DQ<1>
  VSS45  = GND
  DQS0_B_T  = M_B_CPU0_SB_DQS_DP<0>
  DQS0_B_C  = M_B_CPU0_SB_DQS_DN<0>
  VSS46  = GND
  DQ4_B  = M_B_CPU0_SB_DQ<4>
  VSS47  = GND
  DQ5_B  = M_B_CPU0_SB_DQ<5>
  VSS48  = GND
  DQ8_B  = M_B_CPU0_SB_DQ<8>
  VSS49  = GND
  DQ9_B  = M_B_CPU0_SB_DQ<9>
  VSS50  = GND
  DQS1_B_T  = M_B_CPU0_SB_DQS_DP<1>
  DQS1_B_C  = M_B_CPU0_SB_DQS_DN<1>
  VSS51  = GND
  DQ12_B  = M_B_CPU0_SB_DQ<12>
  VSS52  = GND
  DQ13_B  = M_B_CPU0_SB_DQ<13>
  VSS53  = GND
  DQ16_B  = M_B_CPU0_SB_DQ<16>
  VSS54  = GND
  DQ17_B  = M_B_CPU0_SB_DQ<17>
  VSS55  = GND
  DQS2_B_T  = M_B_CPU0_SB_DQS_DP<2>
  DQS2_B_C  = M_B_CPU0_SB_DQS_DN<2>
  VSS56  = GND
  DQ20_B  = M_B_CPU0_SB_DQ<20>
  VSS57  = GND
  DQ21_B  = M_B_CPU0_SB_DQ<21>
  VSS58  = GND
  DQ24_B  = M_B_CPU0_SB_DQ<24>
  VSS59  = GND
  DQ25_B  = M_B_CPU0_SB_DQ<25>
  VSS60  = GND
  DQS3_B_T  = M_B_CPU0_SB_DQS_DP<3>
  DQS3_B_C  = M_B_CPU0_SB_DQS_DN<3>
  VSS61  = GND
  DQ28_B  = M_B_CPU0_SB_DQ<28>
  VSS62  = GND
  DQ29_B  = M_B_CPU0_SB_DQ<29>
  VSS63  = GND
  RFU1  = TP_CHB_CPU0_DIMM1_FRU_1
  VIN_BULK1  = P12V_S3_AUX_CPU0_NVDIMM
  VIN_BULK2  = P12V_S3_AUX_CPU0_NVDIMM
  \pwr_good||fail_n\  = PWRGD_CHB_CPU0_DIMM1
  HSA  = PD_CHB_CPU0_DIMM1_SAA
  RFU2  = TP_CHB_CPU0_DIMM1_FRU_2
  RFU3  = TP_CHB_CPU0_DIMM1_FRU_3
  VSS64  = GND
  DQ2_A  = M_B_CPU0_SA_DQ<2>
  VSS65  = GND
  DQ3_A  = M_B_CPU0_SA_DQ<3>
  VSS66  = GND
  \dqs5_a_c||tdqs5_a_c||dqs5_a_t||tdqs5_a_t\  = M_B_CPU0_SA_DQS_DN<5>
  \dqs5_a_t||tdqs5_a_t\  = M_B_CPU0_SA_DQS_DP<5>
  VSS67  = GND
  DQ6_A  = M_B_CPU0_SA_DQ<6>
  VSS68  = GND
  DQ7_A  = M_B_CPU0_SA_DQ<7>
  VSS69  = GND
  DQ10_A  = M_B_CPU0_SA_DQ<10>
  VSS70  = GND
  DQ11_A  = M_B_CPU0_SA_DQ<11>
  VSS71  = GND
  \dqs6_a_c||tdqs6_a_c||dqs6_a_t||tdqs6_a_t\  = M_B_CPU0_SA_DQS_DN<6>
  \dqs6_a_t||tdqs6_a_t\  = M_B_CPU0_SA_DQS_DP<6>
  VSS72  = GND
  DQ14_A  = M_B_CPU0_SA_DQ<14>
  VSS73  = GND
  DQ15_A  = M_B_CPU0_SA_DQ<15>
  VSS74  = GND
  DQ18_A  = M_B_CPU0_SA_DQ<18>
  VSS75  = GND
  DQ19_A  = M_B_CPU0_SA_DQ<19>
  VSS76  = GND
  \dqs7_a_c||tdqs7_a_c\  = M_B_CPU0_SA_DQS_DN<7>
  \dqs7_a_t||tdqs7_a_t\  = M_B_CPU0_SA_DQS_DP<7>
  VSS77  = GND
  DQ22_A  = M_B_CPU0_SA_DQ<22>
  VSS78  = GND
  DQ23_A  = M_B_CPU0_SA_DQ<23>
  VSS79  = GND
  DQ26_A  = M_B_CPU0_SA_DQ<26>
  VSS80  = GND
  DQ27_A  = M_B_CPU0_SA_DQ<27>
  VSS81  = GND
  \dqs8_a_c||tdqs8_a_c\  = M_B_CPU0_SA_DQS_DN<8>
  \dqs8_a_t||tdqs8_a_t\  = M_B_CPU0_SA_DQS_DP<8>
  VSS82  = GND
  DQ30_A  = M_B_CPU0_SA_DQ<30>
  VSS83  = GND
  DQ31_A  = M_B_CPU0_SA_DQ<31>
  VSS84  = GND
  CB2_A  = M_B_CPU0_SA_CB<2>
  VSS85  = GND
  CB3_A  = M_B_CPU0_SA_CB<3>
  VSS86  = GND
  \dqs9_a_c||tdqs9_a_c\  = M_B_CPU0_SA_DQS_DN<9>
  \dqs9_a_t||tdqs9_a_t\  = M_B_CPU0_SA_DQS_DP<9>
  VSS87  = GND
  CB6_A  = M_B_CPU0_SA_CB<6>
  VSS88  = GND
  CB7_A  = M_B_CPU0_SA_CB<7>
  VSS89  = GND
  RESET_N  = RST_M_AB_CPU0_FPGA_N
  VSS90  = GND
  CS1_A_N  = M_B_CPU0_SA_CS_N<1>
  VSS91  = GND
  CA1_A  = M_B_CPU0_SA_CA<1>
  VSS92  = GND
  CA3_A  = M_B_CPU0_SA_CA<3>
  VSS93  = GND
  CA5_A  = M_B_CPU0_SA_CA<5>
  VSS94  = GND
  CK_T  = M_B_CPU0_CLK_DP<0>
  CK_C  = M_B_CPU0_CLK_DN<0>
  VSS95  = GND
  RFU4  = TP_CHB_CPU0_DIMM1_FRU_4
  CA1_B  = M_B_CPU0_SB_CA<1>
  VSS96  = GND
  CA3_B  = M_B_CPU0_SB_CA<3>
  VSS97  = GND
  CA5_B  = M_B_CPU0_SB_CA<5>
  VSS98  = GND
  PAR_B  = M_B_CPU0_SB_PAR
  VSS99  = GND
  CS1_B_N  = M_B_CPU0_SB_CS_N<1>
  VSS100  = GND
  RFU5  = TP_CHB_CPU0_DIMM1_FRU_5
  RFU6  = TP_CHB_CPU0_DIMM1_FRU_6
  VSS101  = GND
  CB6_B  = M_B_CPU0_SB_CB<6>
  VSS102  = GND
  CB7_B  = M_B_CPU0_SB_CB<7>
  VSS103  = GND
  DQS4_B_C  = M_B_CPU0_SB_DQS_DN<4>
  DQS4_B_T  = M_B_CPU0_SB_DQS_DP<4>
  VSS104  = GND
  CB2_B  = M_B_CPU0_SB_CB<2>
  VSS105  = GND
  CB3_B  = M_B_CPU0_SB_CB<3>
  VSS106  = GND
  DQ2_B  = M_B_CPU0_SB_DQ<2>
  VSS107  = GND
  DQ3_B  = M_B_CPU0_SB_DQ<3>
  VSS108  = GND
  \dqs5_b_c||tdqs5_b_c\  = M_B_CPU0_SB_DQS_DN<5>
  \dqs5_b_t||tdqs5_b_t\  = M_B_CPU0_SB_DQS_DP<5>
  VSS109  = GND
  DQ6_B  = M_B_CPU0_SB_DQ<6>
  VSS110  = GND
  DQ7_B  = M_B_CPU0_SB_DQ<7>
  VSS111  = GND
  DQ10_B  = M_B_CPU0_SB_DQ<10>
  VSS112  = GND
  DQ11_B  = M_B_CPU0_SB_DQ<11>
  VSS113  = GND
  \dqs6_b_c||tdqs6_b_c\  = M_B_CPU0_SB_DQS_DN<6>
  \dqs6_b_t||tdqs6_b_t\  = M_B_CPU0_SB_DQS_DP<6>
  VSS114  = GND
  DQ14_B  = M_B_CPU0_SB_DQ<14>
  VSS115  = GND
  DQ15_B  = M_B_CPU0_SB_DQ<15>
  VSS116  = GND
  DQ18_B  = M_B_CPU0_SB_DQ<18>
  VSS117  = GND
  DQ19_B  = M_B_CPU0_SB_DQ<19>
  VSS118  = GND
  \dqs7_b_c||tdqs7_b_c\  = M_B_CPU0_SB_DQS_DN<7>
  \dqs7_b_t||tdqs7_b_t\  = M_B_CPU0_SB_DQS_DP<7>
  VSS119  = GND
  DQ22_B  = M_B_CPU0_SB_DQ<22>
  VSS120  = GND
  DQ23_B  = M_B_CPU0_SB_DQ<23>
  VSS121  = GND
  DQ26_B  = M_B_CPU0_SB_DQ<26>
  VSS122  = GND
  DQ27_B  = M_B_CPU0_SB_DQ<27>
  VSS123  = GND
  \dqs8_b_c||tdqs8_b_c\  = M_B_CPU0_SB_DQS_DN<8>
  \dqs8_b_t||tdqs8_b_t\  = M_B_CPU0_SB_DQS_DP<8>
  VSS124  = GND
  DQ30_B  = M_B_CPU0_SB_DQ<30>
  VSS125  = GND
  DQ31_B  = M_B_CPU0_SB_DQ<31>
  VSS126  = GND
  G1  = GND
  G2  = GND
  G3  = GND

(kicad_pcb
	(version 20260206)
	(generator "pcbnew")
	(generator_version "10.0")
	(general
		(thickness 1.6)
		(legacy_teardrops no)
	)
	(paper "A4")
	(title_block
		(title "03242023_DA0F0TMBIJ0_F0T_Motherboard_J_brd_V01_OCP.brd")
		(comment 1 "Grand Teton / footprint 2048 of 6105 (J3), pads 138-182 of 291")
	)
	(layers
		(0 "F.Cu" signal "TOP")
		(4 "In1.Cu" signal "GND")
		(6 "In2.Cu" signal "IN1")
		(8 "In3.Cu" signal "GND1")
		(10 "In4.Cu" signal "IN2")
		(12 "In5.Cu" signal "GND2")
		(14 "In6.Cu" signal "IN3")
		(16 "In7.Cu" signal "GND3")
		(18 "In8.Cu" signal "VCC")
		(20 "In9.Cu" signal "VCC1")
		(22 "In10.Cu" signal "GND4")
		(24 "In11.Cu" signal "IN4")
		(26 "In12.Cu" signal "GND5")
		(28 "In13.Cu" signal "IN5")
		(30 "In14.Cu" signal "GND6")
		(32 "In15.Cu" signal "IN6")
		(34 "In16.Cu" signal "GND7")
		(2 "B.Cu" signal "BOTTOM")
		(9 "F.Adhes" user "F.Adhesive")
		(11 "B.Adhes" user "B.Adhesive")
		(13 "F.Paste" user "Package Geometry/Pastemask Top")
		(15 "B.Paste" user "Package Geometry/Pastemask Bottom")
		(5 "F.SilkS" user "Ref Des/Silkscreen Top")
		(7 "B.SilkS" user "Ref Des/Silkscreen Bottom")
		(1 "F.Mask" user "Board Geometry/Soldermask Top")
		(3 "B.Mask" user "Board Geometry/Soldermask Bottom")
		(17 "Dwgs.User" user "User.Drawings")
		(19 "Cmts.User" user "User.Comments")
		(21 "Eco1.User" user "User.Eco1")
		(23 "Eco2.User" user "User.Eco2")
		(25 "Edge.Cuts" user "Board Geometry/Outline")
		(27 "Margin" user)
		(31 "F.CrtYd" user "Package Geometry/Place Bound Top")
		(29 "B.CrtYd" user "Package Geometry/Place Bound Bottom")
		(35 "F.Fab" user "Ref Des/Assembly Top")
		(33 "B.Fab" user "Ref Des/Assembly Bottom")
	)
	(footprint ""
		(layer "F.Cu")
		(at 288.305748 -258.091686)
		(property "Reference" "J3"
			(at -3.683 -81.702148 0)
			(unlocked yes)
			(layer "F.SilkS")
			(effects
				(font
					(size 0.7874 0.5842)
					(thickness 0.1524)
				)
				(justify left)
			)
		)
		(property "Value" ""
			(at 0 0 0)
			(layer "F.Fab")
			(effects
				(font
					(size 1.27 1.27)
				)
			)
		)
		(duplicate_pad_numbers_are_jumpers no)
		(pad "138" smd rect
			(at -2.050034 58.224928 270)
			(size 0.519938 1.4986)
			(layers "F.Cu" "F.Mask" "F.Paste")
			(net "M_B_CPU0_SB_DQS_DN<3>")
		)
		(pad "139" smd rect
			(at -2.050034 59.075066 270)
			(size 0.519938 1.4986)
			(layers "F.Cu" "F.Mask" "F.Paste")
			(net "GND")
		)
		(pad "140" smd rect
			(at -2.050034 59.92495 270)
			(size 0.519938 1.4986)
			(layers "F.Cu" "F.Mask" "F.Paste")
			(net "M_B_CPU0_SB_DQ<28>")
		)
		(pad "141" smd rect
			(at -2.050034 60.775088 270)
			(size 0.519938 1.4986)
			(layers "F.Cu" "F.Mask" "F.Paste")
			(net "GND")
		)
		(pad "142" smd rect
			(at -2.050034 61.624972 270)
			(size 0.519938 1.4986)
			(layers "F.Cu" "F.Mask" "F.Paste")
			(net "M_B_CPU0_SB_DQ<29>")
		)
		(pad "143" smd rect
			(at -2.050034 62.47511 270)
			(size 0.519938 1.4986)
			(layers "F.Cu" "F.Mask" "F.Paste")
			(net "GND")
		)
		(pad "144" smd rect
			(at -2.050034 63.324994 270)
			(size 0.519938 1.4986)
			(layers "F.Cu" "F.Mask" "F.Paste")
			(net "TP_CHB_CPU0_DIMM1_FRU_1")
		)
		(pad "145" smd rect
			(at 2.050034 -63.324994 270)
			(size 0.519938 1.4986)
			(layers "F.Cu" "F.Mask" "F.Paste")
			(net "P12V_S3_AUX_CPU0_NVDIMM")
		)
		(pad "146" smd rect
			(at 2.050034 -62.47511 270)
			(size 0.519938 1.4986)
			(layers "F.Cu" "F.Mask" "F.Paste")
			(net "P12V_S3_AUX_CPU0_NVDIMM")
		)
		(pad "147" smd rect
			(at 2.050034 -61.624972 270)
			(size 0.519938 1.4986)
			(layers "F.Cu" "F.Mask" "F.Paste")
			(net "PWRGD_CHB_CPU0_DIMM1")
		)
		(pad "148" smd rect
			(at 2.050034 -60.775088 270)
			(size 0.519938 1.4986)
			(layers "F.Cu" "F.Mask" "F.Paste")
			(net "PD_CHB_CPU0_DIMM1_SAA")
		)
		(pad "149" smd rect
			(at 2.050034 -59.92495 270)
			(size 0.519938 1.4986)
			(layers "F.Cu" "F.Mask" "F.Paste")
			(net "TP_CHB_CPU0_DIMM1_FRU_2")
		)
		(pad "150" smd rect
			(at 2.050034 -59.075066 270)
			(size 0.519938 1.4986)
			(layers "F.Cu" "F.Mask" "F.Paste")
			(net "TP_CHB_CPU0_DIMM1_FRU_3")
		)
		(pad "151" smd rect
			(at 2.050034 -58.224928 270)
			(size 0.519938 1.4986)
			(layers "F.Cu" "F.Mask" "F.Paste")
			(net "GND")
		)
		(pad "152" smd rect
			(at 2.050034 -57.375044 270)
			(size 0.519938 1.4986)
			(layers "F.Cu" "F.Mask" "F.Paste")
			(net "M_B_CPU0_SA_DQ<2>")
		)
		(pad "153" smd rect
			(at 2.050034 -56.524906 270)
			(size 0.519938 1.4986)
			(layers "F.Cu" "F.Mask" "F.Paste")
			(net "GND")
		)
		(pad "154" smd rect
			(at 2.050034 -55.675022 270)
			(size 0.519938 1.4986)
			(layers "F.Cu" "F.Mask" "F.Paste")
			(net "M_B_CPU0_SA_DQ<3>")
		)
		(pad "155" smd rect
			(at 2.050034 -54.824884 270)
			(size 0.519938 1.4986)
			(layers "F.Cu" "F.Mask" "F.Paste")
			(net "GND")
		)
		(pad "156" smd rect
			(at 2.050034 -53.975 270)
			(size 0.519938 1.4986)
			(layers "F.Cu" "F.Mask" "F.Paste")
			(net "M_B_CPU0_SA_DQS_DN<5>")
		)
		(pad "157" smd rect
			(at 2.050034 -53.125116 270)
			(size 0.519938 1.4986)
			(layers "F.Cu" "F.Mask" "F.Paste")
			(net "M_B_CPU0_SA_DQS_DP<5>")
		)
		(pad "158" smd rect
			(at 2.050034 -52.274978 270)
			(size 0.519938 1.4986)
			(layers "F.Cu" "F.Mask" "F.Paste")
			(net "GND")
		)
		(pad "159" smd rect
			(at 2.050034 -51.425094 270)
			(size 0.519938 1.4986)
			(layers "F.Cu" "F.Mask" "F.Paste")
			(net "M_B_CPU0_SA_DQ<6>")
		)
		(pad "160" smd rect
			(at 2.050034 -50.574956 270)
			(size 0.519938 1.4986)
			(layers "F.Cu" "F.Mask" "F.Paste")
			(net "GND")
		)
		(pad "161" smd rect
			(at 2.050034 -49.725072 270)
			(size 0.519938 1.4986)
			(layers "F.Cu" "F.Mask" "F.Paste")
			(net "M_B_CPU0_SA_DQ<7>")
		)
		(pad "162" smd rect
			(at 2.050034 -48.874934 270)
			(size 0.519938 1.4986)
			(layers "F.Cu" "F.Mask" "F.Paste")
			(net "GND")
		)
		(pad "163" smd rect
			(at 2.050034 -48.02505 270)
			(size 0.519938 1.4986)
			(layers "F.Cu" "F.Mask" "F.Paste")
			(net "M_B_CPU0_SA_DQ<10>")
		)
		(pad "164" smd rect
			(at 2.050034 -47.174912 270)
			(size 0.519938 1.4986)
			(layers "F.Cu" "F.Mask" "F.Paste")
			(net "GND")
		)
		(pad "165" smd rect
			(at 2.050034 -46.325028 270)
			(size 0.519938 1.4986)
			(layers "F.Cu" "F.Mask" "F.Paste")
			(net "M_B_CPU0_SA_DQ<11>")
		)
		(pad "166" smd rect
			(at 2.050034 -45.47489 270)
			(size 0.519938 1.4986)
			(layers "F.Cu" "F.Mask" "F.Paste")
			(net "GND")
		)
		(pad "167" smd rect
			(at 2.050034 -44.625006 270)
			(size 0.519938 1.4986)
			(layers "F.Cu" "F.Mask" "F.Paste")
			(net "M_B_CPU0_SA_DQS_DN<6>")
		)
		(pad "168" smd rect
			(at 2.050034 -43.775122 270)
			(size 0.519938 1.4986)
			(layers "F.Cu" "F.Mask" "F.Paste")
			(net "M_B_CPU0_SA_DQS_DP<6>")
		)
		(pad "169" smd rect
			(at 2.050034 -42.924984 270)
			(size 0.519938 1.4986)
			(layers "F.Cu" "F.Mask" "F.Paste")
			(net "GND")
		)
		(pad "170" smd rect
			(at 2.050034 -42.0751 270)
			(size 0.519938 1.4986)
			(layers "F.Cu" "F.Mask" "F.Paste")
			(net "M_B_CPU0_SA_DQ<14>")
		)
		(pad "171" smd rect
			(at 2.050034 -41.224962 270)
			(size 0.519938 1.4986)
			(layers "F.Cu" "F.Mask" "F.Paste")
			(net "GND")
		)
		(pad "172" smd rect
			(at 2.050034 -40.375078 270)
			(size 0.519938 1.4986)
			(layers "F.Cu" "F.Mask" "F.Paste")
			(net "M_B_CPU0_SA_DQ<15>")
		)
		(pad "173" smd rect
			(at 2.050034 -39.52494 270)
			(size 0.519938 1.4986)
			(layers "F.Cu" "F.Mask" "F.Paste")
			(net "GND")
		)
		(pad "174" smd rect
			(at 2.050034 -38.675056 270)
			(size 0.519938 1.4986)
			(layers "F.Cu" "F.Mask" "F.Paste")
			(net "M_B_CPU0_SA_DQ<18>")
		)
		(pad "175" smd rect
			(at 2.050034 -37.824918 270)
			(size 0.519938 1.4986)
			(layers "F.Cu" "F.Mask" "F.Paste")
			(net "GND")
		)
		(pad "176" smd rect
			(at 2.050034 -36.975034 270)
			(size 0.519938 1.4986)
			(layers "F.Cu" "F.Mask" "F.Paste")
			(net "M_B_CPU0_SA_DQ<19>")
		)
		(pad "177" smd rect
			(at 2.050034 -36.124896 270)
			(size 0.519938 1.4986)
			(layers "F.Cu" "F.Mask" "F.Paste")
			(net "GND")
		)
		(pad "178" smd rect
			(at 2.050034 -35.275012 270)
			(size 0.519938 1.4986)
			(layers "F.Cu" "F.Mask" "F.Paste")
			(net "M_B_CPU0_SA_DQS_DN<7>")
		)
		(pad "179" smd rect
			(at 2.050034 -34.425128 270)
			(size 0.519938 1.4986)
			(layers "F.Cu" "F.Mask" "F.Paste")
			(net "M_B_CPU0_SA_DQS_DP<7>")
		)
		(pad "180" smd rect
			(at 2.050034 -33.57499 270)
			(size 0.519938 1.4986)
			(layers "F.Cu" "F.Mask" "F.Paste")
			(net "GND")
		)
		(pad "181" smd rect
			(at 2.050034 -32.725106 270)
			(size 0.519938 1.4986)
			(layers "F.Cu" "F.Mask" "F.Paste")
			(net "M_B_CPU0_SA_DQ<22>")
		)
		(pad "182" smd rect
			(at 2.050034 -31.874968 270)
			(size 0.519938 1.4986)
			(layers "F.Cu" "F.Mask" "F.Paste")
			(net "GND")
		)
	)
)
